# S9S_MB_2U (Grand Teton) — schematic netlist excerpt (pin names and nets, part order shuffled) for the footprints in the layout excerpt that follows; sources: Cadence DE-HDL packaged netlist, KiCad conversion of 03242023_DA0F0TMBIJ0_F0T_Motherboard_J_brd_V01_OCP.brd

PC444_P1_1  Q_CAP  1UF 16V 10% X6S  pkg C0402  page 293 : A = SW_P12V_PVCCINFAON_CPU1_FLT ; B = GND
R651  Q_RES  2.2K 5% CHIP  pkg 0402LF  page 231 : A = P3V3_AUX ; B = SMB_FRU_3V3AUX_SCL

(kicad_pcb
	(version 20260206)
	(generator "pcbnew")
	(generator_version "10.0")
	(general
		(thickness 1.6)
		(legacy_teardrops no)
	)
	(paper "A4")
	(title_block
		(title "03242023_DA0F0TMBIJ0_F0T_Motherboard_J_brd_V01_OCP.brd")
		(comment 1 "Grand Teton / footprints 1875-1876 of 6105")
	)
	(layers
		(0 "F.Cu" signal "TOP")
		(4 "In1.Cu" signal "GND")
		(6 "In2.Cu" signal "IN1")
		(8 "In3.Cu" signal "GND1")
		(10 "In4.Cu" signal "IN2")
		(12 "In5.Cu" signal "GND2")
		(14 "In6.Cu" signal "IN3")
		(16 "In7.Cu" signal "GND3")
		(18 "In8.Cu" signal "VCC")
		(20 "In9.Cu" signal "VCC1")
		(22 "In10.Cu" signal "GND4")
		(24 "In11.Cu" signal "IN4")
		(26 "In12.Cu" signal "GND5")
		(28 "In13.Cu" signal "IN5")
		(30 "In14.Cu" signal "GND6")
		(32 "In15.Cu" signal "IN6")
		(34 "In16.Cu" signal "GND7")
		(2 "B.Cu" signal "BOTTOM")
		(9 "F.Adhes" user "F.Adhesive")
		(11 "B.Adhes" user "B.Adhesive")
		(13 "F.Paste" user "Package Geometry/Pastemask Top")
		(15 "B.Paste" user "Package Geometry/Pastemask Bottom")
		(5 "F.SilkS" user "Ref Des/Silkscreen Top")
		(7 "B.SilkS" user "Ref Des/Silkscreen Bottom")
		(1 "F.Mask" user "Board Geometry/Soldermask Top")
		(3 "B.Mask" user "Board Geometry/Soldermask Bottom")
		(17 "Dwgs.User" user "User.Drawings")
		(19 "Cmts.User" user "User.Comments")
		(21 "Eco1.User" user "User.Eco1")
		(23 "Eco2.User" user "User.Eco2")
		(25 "Edge.Cuts" user "Board Geometry/Outline")
		(27 "Margin" user)
		(31 "F.CrtYd" user "Package Geometry/Place Bound Top")
		(29 "B.CrtYd" user "Package Geometry/Place Bound Bottom")
		(35 "F.Fab" user "Ref Des/Assembly Top")
		(33 "B.Fab" user "Ref Des/Assembly Bottom")
	)
	(footprint ""
		(layer "F.Cu")
		(at 131.466844 -131.310126 180)
		(property "Reference" "R651"
			(at 0 0 180)
			(layer "F.SilkS")
			(hide yes)
			(effects
				(font
					(size 1.27 1.27)
				)
			)
		)
		(property "Value" ""
			(at 0 0 180)
			(layer "F.Fab")
			(effects
				(font
					(size 1.27 1.27)
				)
			)
		)
		(duplicate_pad_numbers_are_jumpers no)
		(fp_line
			(start 0.7874 0.4064)
			(end -0.7874 0.4064)
			(stroke
				(width 0.1524)
				(type default)
			)
			(layer "F.SilkS")
		)
		(fp_line
			(start 0.7874 -0.4064)
			(end 0.7874 0.4064)
			(stroke
				(width 0.1524)
				(type default)
			)
			(layer "F.SilkS")
		)
		(fp_line
			(start -0.7874 0.4064)
			(end -0.7874 -0.4064)
			(stroke
				(width 0.1524)
				(type default)
			)
			(layer "F.SilkS")
		)
		(fp_line
			(start -0.7874 -0.4064)
			(end 0.7874 -0.4064)
			(stroke
				(width 0.1524)
				(type default)
			)
			(layer "F.SilkS")
		)
		(fp_line
			(start 0.67945 0.3048)
			(end 0.120396 0.3048)
			(stroke
				(width 0.1)
				(type default)
			)
			(layer "F.Fab")
		)
		(fp_line
			(start 0.67945 -0.3048)
			(end 0.67945 0.3048)
			(stroke
				(width 0.1)
				(type default)
			)
			(layer "F.Fab")
		)
		(fp_line
			(start 0.12065 -0.2794)
			(end 0.12065 -0.3048)
			(stroke
				(width 0.1)
				(type default)
			)
			(layer "F.Fab")
		)
		(fp_line
			(start 0.12065 -0.3048)
			(end 0.67945 -0.3048)
			(stroke
				(width 0.1)
				(type default)
			)
			(layer "F.Fab")
		)
		(fp_line
			(start 0.120396 0.3048)
			(end 0.120396 0.2794)
			(stroke
				(width 0.1)
				(type default)
			)
			(layer "F.Fab")
		)
		(fp_line
			(start 0.120396 0.2794)
			(end -0.12065 0.2794)
			(stroke
				(width 0.1)
				(type default)
			)
			(layer "F.Fab")
		)
		(fp_line
			(start -0.12065 0.3048)
			(end -0.67945 0.3048)
			(stroke
				(width 0.1)
				(type default)
			)
			(layer "F.Fab")
		)
		(fp_line
			(start -0.12065 0.2794)
			(end -0.12065 0.3048)
			(stroke
				(width 0.1)
				(type default)
			)
			(layer "F.Fab")
		)
		(fp_line
			(start -0.12065 -0.2794)
			(end 0.12065 -0.2794)
			(stroke
				(width 0.1)
				(type default)
			)
			(layer "F.Fab")
		)
		(fp_line
			(start -0.12065 -0.305054)
			(end -0.12065 -0.2794)
			(stroke
				(width 0.1)
				(type default)
			)
			(layer "F.Fab")
		)
		(fp_line
			(start -0.67945 0.3048)
			(end -0.67945 -0.305054)
			(stroke
				(width 0.1)
				(type default)
			)
			(layer "F.Fab")
		)
		(fp_line
			(start -0.67945 -0.305054)
			(end -0.12065 -0.305054)
			(stroke
				(width 0.1)
				(type default)
			)
			(layer "F.Fab")
		)
		(pad "1" smd circle
			(at -0.40005 0 180)
			(size 0 0)
			(layers "F.Cu" "F.Mask" "F.Paste")
			(net "P3V3_AUX")
		)
		(pad "2" smd circle
			(at 0.40005 0 180)
			(size 0 0)
			(layers "F.Cu" "F.Mask" "F.Paste")
			(net "SMB_FRU_3V3AUX_SCL")
		)
	)
	(footprint ""
		(layer "F.Cu")
		(at 54.811168 -160.047178)
		(property "Reference" "PC444_P1_1"
			(at 0 0 0)
			(layer "F.SilkS")
			(hide yes)
			(effects
				(font
					(size 1.27 1.27)
				)
			)
		)
		(property "Value" ""
			(at 0 0 0)
			(layer "F.Fab")
			(effects
				(font
					(size 1.27 1.27)
				)
			)
		)
		(duplicate_pad_numbers_are_jumpers no)
		(fp_line
			(start -0.7874 -0.4064)
			(end 0.7874 -0.4064)
			(stroke
				(width 0.1524)
				(type default)
			)
			(layer "F.SilkS")
		)
		(fp_line
			(start -0.7874 0.4064)
			(end -0.7874 -0.4064)
			(stroke
				(width 0.1524)
				(type default)
			)
			(layer "F.SilkS")
		)
		(fp_line
			(start 0.7874 -0.4064)
			(end 0.7874 0.4064)
			(stroke
				(width 0.1524)
				(type default)
			)
			(layer "F.SilkS")
		)
		(fp_line
			(start 0.7874 0.4064)
			(end -0.7874 0.4064)
			(stroke
				(width 0.1524)
				(type default)
			)
			(layer "F.SilkS")
		)
		(fp_line
			(start -0.67945 -0.305054)
			(end -0.12065 -0.305054)
			(stroke
				(width 0.1)
				(type default)
			)
			(layer "F.Fab")
		)
		(fp_line
			(start -0.67945 0.3048)
			(end -0.67945 -0.305054)
			(stroke
				(width 0.1)
				(type default)
			)
			(layer "F.Fab")
		)
		(fp_line
			(start -0.12065 -0.305054)
			(end -0.12065 -0.2794)
			(stroke
				(width 0.1)
				(type default)
			)
			(layer "F.Fab")
		)
		(fp_line
			(start -0.12065 -0.2794)
			(end 0.12065 -0.2794)
			(stroke
				(width 0.1)
				(type default)
			)
			(layer "F.Fab")
		)
		(fp_line
			(start -0.12065 0.2794)
			(end -0.12065 0.3048)
			(stroke
				(width 0.1)
				(type default)
			)
			(layer "F.Fab")
		)
		(fp_line
			(start -0.12065 0.3048)
			(end -0.67945 0.3048)
			(stroke
				(width 0.1)
				(type default)
			)
			(layer "F.Fab")
		)
		(fp_line
			(start 0.120396 0.2794)
			(end -0.12065 0.2794)
			(stroke
				(width 0.1)
				(type default)
			)
			(layer "F.Fab")
		)
		(fp_line
			(start 0.120396 0.3048)
			(end 0.120396 0.2794)
			(stroke
				(width 0.1)
				(type default)
			)
			(layer "F.Fab")
		)
		(fp_line
			(start 0.12065 -0.3048)
			(end 0.67945 -0.3048)
			(stroke
				(width 0.1)
				(type default)
			)
			(layer "F.Fab")
		)
		(fp_line
			(start 0.12065 -0.2794)
			(end 0.12065 -0.3048)
			(stroke
				(width 0.1)
				(type default)
			)
			(layer "F.Fab")
		)
		(fp_line
			(start 0.67945 -0.3048)
			(end 0.67945 0.3048)
			(stroke
				(width 0.1)
				(type default)
			)
			(layer "F.Fab")
		)
		(fp_line
			(start 0.67945 0.3048)
			(end 0.120396 0.3048)
			(stroke
				(width 0.1)
				(type default)
			)
			(layer "F.Fab")
		)
		(pad "1" smd circle
			(at -0.40005 0)
			(size 0 0)
			(layers "F.Cu" "F.Mask" "F.Paste")
			(net "SW_P12V_PVCCINFAON_CPU1_FLT")
		)
		(pad "2" smd circle
			(at 0.40005 0)
			(size 0 0)
			(layers "F.Cu" "F.Mask" "F.Paste")
			(net "GND")
		)
	)
)
